(kicad_pcb
	(version 20260206)
	(generator "pcbnew")
	(generator_version "10.0")
	(general
		(thickness 1.6)
		(legacy_teardrops no)
	)
	(paper "A4")
	(title_block
		(title "01162023_DA0F0TEBIF0_F0T_Expander_BD_F_brd_V02_OCP.brd")
		(comment 1 "Grand Teton / footprint 6602 of 9728 (PEX1), pads 2120-2237 of 2397")
	)
	(layers
		(0 "F.Cu" signal "TOP")
		(4 "In1.Cu" signal "GND")
		(6 "In2.Cu" signal "VCC")
		(8 "In3.Cu" signal "VCC1")
		(10 "In4.Cu" signal "GND1")
		(12 "In5.Cu" signal "IN1")
		(14 "In6.Cu" signal "GND2")
		(16 "In7.Cu" signal "IN2")
		(18 "In8.Cu" signal "GND3")
		(20 "In9.Cu" signal "IN3")
		(22 "In10.Cu" signal "GND4")
		(24 "In11.Cu" signal "IN4")
		(26 "In12.Cu" signal "GND5")
		(28 "In13.Cu" signal "IN5")
		(30 "In14.Cu" signal "GND6")
		(32 "In15.Cu" signal "IN6")
		(34 "In16.Cu" signal "GND7")
		(2 "B.Cu" signal "BOTTOM")
		(9 "F.Adhes" user "F.Adhesive")
		(11 "B.Adhes" user "B.Adhesive")
		(13 "F.Paste" user "Package Geometry/Pastemask Top")
		(15 "B.Paste" user "Package Geometry/Pastemask Bottom")
		(5 "F.SilkS" user "Ref Des/Silkscreen Top")
		(7 "B.SilkS" user "Ref Des/Silkscreen Bottom")
		(1 "F.Mask" user "Board Geometry/Soldermask Top")
		(3 "B.Mask" user "Board Geometry/Soldermask Bottom")
		(17 "Dwgs.User" user "User.Drawings")
		(19 "Cmts.User" user "User.Comments")
		(21 "Eco1.User" user "User.Eco1")
		(23 "Eco2.User" user "User.Eco2")
		(25 "Edge.Cuts" user "Board Geometry/Outline")
		(27 "Margin" user)
		(31 "F.CrtYd" user "Package Geometry/Place Bound Top")
		(29 "B.CrtYd" user "Package Geometry/Place Bound Bottom")
		(35 "F.Fab" user "Ref Des/Assembly Top")
		(33 "B.Fab" user "Ref Des/Assembly Bottom")
	)
	(footprint ""
		(layer "F.Cu")
		(at 175.749966 -295.89984)
		(property "Reference" "PEX1"
			(at -3.353562 35.593274 0)
			(unlocked yes)
			(layer "F.SilkS")
			(effects
				(font
					(size 2.032 1.524)
					(thickness 0.1524)
				)
				(justify left)
			)
		)
		(property "Value" ""
			(at 0 0 0)
			(layer "F.Fab")
			(effects
				(font
					(size 1.27 1.27)
				)
			)
		)
		(duplicate_pad_numbers_are_jumpers no)
		(pad "R17" smd circle
			(at -7.599934 -9.500108)
			(size 0.4572 0.4572)
			(layers "F.Cu" "F.Mask" "F.Paste")
			(net "GND")
		)
		(pad "R18" smd circle
			(at -6.649974 -9.500108)
			(size 0.4572 0.4572)
			(layers "F.Cu" "F.Mask" "F.Paste")
			(net "GND")
		)
		(pad "R19" smd circle
			(at -5.700014 -9.500108)
			(size 0.4572 0.4572)
			(layers "F.Cu" "F.Mask" "F.Paste")
			(net "GND")
		)
		(pad "R20" smd circle
			(at -4.750054 -9.500108)
			(size 0.4572 0.4572)
			(layers "F.Cu" "F.Mask" "F.Paste")
			(net "GND")
		)
		(pad "R21" smd circle
			(at -3.800094 -9.500108)
			(size 0.4572 0.4572)
			(layers "F.Cu" "F.Mask" "F.Paste")
			(net "GND")
		)
		(pad "R22" smd circle
			(at -2.84988 -9.500108)
			(size 0.4572 0.4572)
			(layers "F.Cu" "F.Mask" "F.Paste")
			(net "GND")
		)
		(pad "R23" smd circle
			(at -1.89992 -9.500108)
			(size 0.4572 0.4572)
			(layers "F.Cu" "F.Mask" "F.Paste")
			(net "GND")
		)
		(pad "R24" smd circle
			(at -0.94996 -9.500108)
			(size 0.4572 0.4572)
			(layers "F.Cu" "F.Mask" "F.Paste")
			(net "GND")
		)
		(pad "R25" smd circle
			(at 0 -9.500108)
			(size 0.4572 0.4572)
			(layers "F.Cu" "F.Mask" "F.Paste")
			(net "GND")
		)
		(pad "R26" smd circle
			(at 0.94996 -9.500108)
			(size 0.4572 0.4572)
			(layers "F.Cu" "F.Mask" "F.Paste")
			(net "GND")
		)
		(pad "R27" smd circle
			(at 1.89992 -9.500108)
			(size 0.4572 0.4572)
			(layers "F.Cu" "F.Mask" "F.Paste")
			(net "GND")
		)
		(pad "R28" smd circle
			(at 2.84988 -9.500108)
			(size 0.4572 0.4572)
			(layers "F.Cu" "F.Mask" "F.Paste")
			(net "GND")
		)
		(pad "R29" smd circle
			(at 3.800094 -9.500108)
			(size 0.4572 0.4572)
			(layers "F.Cu" "F.Mask" "F.Paste")
			(net "GND")
		)
		(pad "R30" smd circle
			(at 4.750054 -9.500108)
			(size 0.4572 0.4572)
			(layers "F.Cu" "F.Mask" "F.Paste")
			(net "GND")
		)
		(pad "R31" smd circle
			(at 5.700014 -9.500108)
			(size 0.4572 0.4572)
			(layers "F.Cu" "F.Mask" "F.Paste")
			(net "GND")
		)
		(pad "R32" smd circle
			(at 6.649974 -9.500108)
			(size 0.4572 0.4572)
			(layers "F.Cu" "F.Mask" "F.Paste")
			(net "GND")
		)
		(pad "R33" smd circle
			(at 7.599934 -9.500108)
			(size 0.4572 0.4572)
			(layers "F.Cu" "F.Mask" "F.Paste")
			(net "GND")
		)
		(pad "R34" smd circle
			(at 8.549894 -9.500108)
			(size 0.4572 0.4572)
			(layers "F.Cu" "F.Mask" "F.Paste")
			(net "GND")
		)
		(pad "R35" smd circle
			(at 9.500108 -9.500108)
			(size 0.4572 0.4572)
			(layers "F.Cu" "F.Mask" "F.Paste")
			(net "GND")
		)
		(pad "R36" smd circle
			(at 10.450068 -9.500108)
			(size 0.4572 0.4572)
			(layers "F.Cu" "F.Mask" "F.Paste")
			(net "Net_497")
		)
		(pad "R37" smd circle
			(at 11.400028 -9.500108)
			(size 0.4572 0.4572)
			(layers "F.Cu" "F.Mask" "F.Paste")
			(net "GND")
		)
		(pad "R38" smd circle
			(at 12.349988 -9.500108)
			(size 0.4572 0.4572)
			(layers "F.Cu" "F.Mask" "F.Paste")
			(net "Net_5228")
		)
		(pad "R39" smd circle
			(at 13.299948 -9.500108)
			(size 0.4572 0.4572)
			(layers "F.Cu" "F.Mask" "F.Paste")
			(net "Net_5222")
		)
		(pad "R40" smd circle
			(at 14.249908 -9.500108)
			(size 0.4572 0.4572)
			(layers "F.Cu" "F.Mask" "F.Paste")
			(net "GND")
		)
		(pad "R41" smd circle
			(at 15.200122 -9.500108)
			(size 0.4572 0.4572)
			(layers "F.Cu" "F.Mask" "F.Paste")
			(net "GND")
		)
		(pad "R42" smd circle
			(at 16.150082 -9.500108)
			(size 0.4572 0.4572)
			(layers "F.Cu" "F.Mask" "F.Paste")
			(net "GND")
		)
		(pad "R43" smd circle
			(at 17.100042 -9.500108)
			(size 0.4572 0.4572)
			(layers "F.Cu" "F.Mask" "F.Paste")
			(net "P5E_PEX1_STN4_TX_DP<65>")
		)
		(pad "R44" smd circle
			(at 18.050002 -9.500108)
			(size 0.4572 0.4572)
			(layers "F.Cu" "F.Mask" "F.Paste")
			(net "P5E_PEX1_STN4_TX_DN<65>")
		)
		(pad "R45" smd circle
			(at 18.999962 -9.500108)
			(size 0.4572 0.4572)
			(layers "F.Cu" "F.Mask" "F.Paste")
			(net "GND")
		)
		(pad "R46" smd circle
			(at 19.949922 -9.500108)
			(size 0.4572 0.4572)
			(layers "F.Cu" "F.Mask" "F.Paste")
			(net "P5E_PEX1_STN4_RX_DP<65>")
		)
		(pad "R47" smd circle
			(at 20.899882 -9.500108)
			(size 0.4572 0.4572)
			(layers "F.Cu" "F.Mask" "F.Paste")
			(net "P5E_PEX1_STN4_RX_DN<65>")
		)
		(pad "R48" smd circle
			(at 21.850096 -9.500108)
			(size 0.4572 0.4572)
			(layers "F.Cu" "F.Mask" "F.Paste")
			(net "GND")
		)
		(pad "R49" smd circle
			(at 22.800056 -9.500108)
			(size 0.4572 0.4572)
			(layers "F.Cu" "F.Mask" "F.Paste")
			(net "GND")
		)
		(pad "T1" smd circle
			(at -22.800056 -8.549894)
			(size 0.4572 0.4572)
			(layers "F.Cu" "F.Mask" "F.Paste")
			(net "P5E_PEX1_STN7_RX_DN<115>")
		)
		(pad "T2" smd circle
			(at -21.850096 -8.549894)
			(size 0.4572 0.4572)
			(layers "F.Cu" "F.Mask" "F.Paste")
			(net "P5E_PEX1_STN7_RX_DP<115>")
		)
		(pad "T3" smd circle
			(at -20.899882 -8.549894)
			(size 0.4572 0.4572)
			(layers "F.Cu" "F.Mask" "F.Paste")
			(net "GND")
		)
		(pad "T4" smd circle
			(at -19.949922 -8.549894)
			(size 0.4572 0.4572)
			(layers "F.Cu" "F.Mask" "F.Paste")
			(net "GND")
		)
		(pad "T5" smd circle
			(at -18.999962 -8.549894)
			(size 0.4572 0.4572)
			(layers "F.Cu" "F.Mask" "F.Paste")
			(net "GND")
		)
		(pad "T6" smd circle
			(at -18.050002 -8.549894)
			(size 0.4572 0.4572)
			(layers "F.Cu" "F.Mask" "F.Paste")
			(net "GND")
		)
		(pad "T7" smd circle
			(at -17.100042 -8.549894)
			(size 0.4572 0.4572)
			(layers "F.Cu" "F.Mask" "F.Paste")
			(net "GND")
		)
		(pad "T8" smd circle
			(at -16.150082 -8.549894)
			(size 0.4572 0.4572)
			(layers "F.Cu" "F.Mask" "F.Paste")
			(net "P5E_PEX1_STN7_TX_DN<115>")
		)
		(pad "T9" smd circle
			(at -15.200122 -8.549894)
			(size 0.4572 0.4572)
			(layers "F.Cu" "F.Mask" "F.Paste")
			(net "P5E_PEX1_STN7_TX_DP<115>")
		)
		(pad "T10" smd circle
			(at -14.249908 -8.549894)
			(size 0.4572 0.4572)
			(layers "F.Cu" "F.Mask" "F.Paste")
			(net "GND")
		)
		(pad "T11" smd circle
			(at -13.299948 -8.549894)
			(size 0.4572 0.4572)
			(layers "F.Cu" "F.Mask" "F.Paste")
			(net "GND")
		)
		(pad "T12" smd circle
			(at -12.349988 -8.549894)
			(size 0.4572 0.4572)
			(layers "F.Cu" "F.Mask" "F.Paste")
			(net "GND")
		)
		(pad "T13" smd circle
			(at -11.400028 -8.549894)
			(size 0.4572 0.4572)
			(layers "F.Cu" "F.Mask" "F.Paste")
			(net "GND")
		)
		(pad "T14" smd circle
			(at -10.450068 -8.549894)
			(size 0.4572 0.4572)
			(layers "F.Cu" "F.Mask" "F.Paste")
			(net "Net_504")
		)
		(pad "T15" smd circle
			(at -9.500108 -8.549894)
			(size 0.4572 0.4572)
			(layers "F.Cu" "F.Mask" "F.Paste")
			(net "GND")
		)
		(pad "T16" smd circle
			(at -8.549894 -8.549894)
			(size 0.4572 0.4572)
			(layers "F.Cu" "F.Mask" "F.Paste")
			(net "P1V25_SERDES_VDDPLL_PEX1")
		)
		(pad "T17" smd circle
			(at -7.599934 -8.549894)
			(size 0.4572 0.4572)
			(layers "F.Cu" "F.Mask" "F.Paste")
			(net "P1V25_SERDES_VDDPLL_PEX1")
		)
		(pad "T18" smd circle
			(at -6.649974 -8.549894)
			(size 0.4572 0.4572)
			(layers "F.Cu" "F.Mask" "F.Paste")
			(net "P1V25_SERDES_VDDPLL_PEX1")
		)
		(pad "T19" smd circle
			(at -5.700014 -8.549894)
			(size 0.4572 0.4572)
			(layers "F.Cu" "F.Mask" "F.Paste")
			(net "P1V25_SERDES_VDDPLL_PEX1")
		)
		(pad "T20" smd circle
			(at -4.750054 -8.549894)
			(size 0.4572 0.4572)
			(layers "F.Cu" "F.Mask" "F.Paste")
			(net "P1V25_SERDES_VDDPLL_PEX1")
		)
		(pad "T21" smd circle
			(at -3.800094 -8.549894)
			(size 0.4572 0.4572)
			(layers "F.Cu" "F.Mask" "F.Paste")
			(net "P1V25_SERDES_VDDPLL_PEX1")
		)
		(pad "T22" smd circle
			(at -2.84988 -8.549894)
			(size 0.4572 0.4572)
			(layers "F.Cu" "F.Mask" "F.Paste")
			(net "P1V25_SERDES_VDDPLL_PEX1")
		)
		(pad "T23" smd circle
			(at -1.89992 -8.549894)
			(size 0.4572 0.4572)
			(layers "F.Cu" "F.Mask" "F.Paste")
			(net "P1V25_SERDES_VDDPLL_PEX1")
		)
		(pad "T24" smd circle
			(at -0.94996 -8.549894)
			(size 0.4572 0.4572)
			(layers "F.Cu" "F.Mask" "F.Paste")
			(net "P1V25_SERDES_VDDPLL_PEX1")
		)
		(pad "T25" smd circle
			(at 0 -8.549894)
			(size 0.4572 0.4572)
			(layers "F.Cu" "F.Mask" "F.Paste")
			(net "P1V25_SERDES_VDDPLL_PEX1")
		)
		(pad "T26" smd circle
			(at 0.94996 -8.549894)
			(size 0.4572 0.4572)
			(layers "F.Cu" "F.Mask" "F.Paste")
			(net "P1V25_SERDES_VDDPLL_PEX1")
		)
		(pad "T27" smd circle
			(at 1.89992 -8.549894)
			(size 0.4572 0.4572)
			(layers "F.Cu" "F.Mask" "F.Paste")
			(net "P1V25_SERDES_VDDPLL_PEX1")
		)
		(pad "T28" smd circle
			(at 2.84988 -8.549894)
			(size 0.4572 0.4572)
			(layers "F.Cu" "F.Mask" "F.Paste")
			(net "P1V25_SERDES_VDDPLL_PEX1")
		)
		(pad "T29" smd circle
			(at 3.800094 -8.549894)
			(size 0.4572 0.4572)
			(layers "F.Cu" "F.Mask" "F.Paste")
			(net "P1V25_SERDES_VDDPLL_PEX1")
		)
		(pad "T30" smd circle
			(at 4.750054 -8.549894)
			(size 0.4572 0.4572)
			(layers "F.Cu" "F.Mask" "F.Paste")
			(net "P1V25_SERDES_VDDPLL_PEX1")
		)
		(pad "T31" smd circle
			(at 5.700014 -8.549894)
			(size 0.4572 0.4572)
			(layers "F.Cu" "F.Mask" "F.Paste")
			(net "P1V25_SERDES_VDDPLL_PEX1")
		)
		(pad "T32" smd circle
			(at 6.649974 -8.549894)
			(size 0.4572 0.4572)
			(layers "F.Cu" "F.Mask" "F.Paste")
			(net "P1V25_SERDES_VDDPLL_PEX1")
		)
		(pad "T33" smd circle
			(at 7.599934 -8.549894)
			(size 0.4572 0.4572)
			(layers "F.Cu" "F.Mask" "F.Paste")
			(net "P1V25_SERDES_VDDPLL_PEX1")
		)
		(pad "T34" smd circle
			(at 8.549894 -8.549894)
			(size 0.4572 0.4572)
			(layers "F.Cu" "F.Mask" "F.Paste")
			(net "GND")
		)
		(pad "T35" smd circle
			(at 9.500108 -8.549894)
			(size 0.4572 0.4572)
			(layers "F.Cu" "F.Mask" "F.Paste")
			(net "P1V8_VDDA_PEX1")
		)
		(pad "T36" smd circle
			(at 10.450068 -8.549894)
			(size 0.4572 0.4572)
			(layers "F.Cu" "F.Mask" "F.Paste")
			(net "Net_496")
		)
		(pad "T37" smd circle
			(at 11.400028 -8.549894)
			(size 0.4572 0.4572)
			(layers "F.Cu" "F.Mask" "F.Paste")
			(net "GND")
		)
		(pad "T38" smd circle
			(at 12.349988 -8.549894)
			(size 0.4572 0.4572)
			(layers "F.Cu" "F.Mask" "F.Paste")
			(net "RST_PEX1_S0_PERST_R_N")
		)
		(pad "T39" smd circle
			(at 13.299948 -8.549894)
			(size 0.4572 0.4572)
			(layers "F.Cu" "F.Mask" "F.Paste")
			(net "Net_391")
		)
		(pad "T40" smd circle
			(at 14.249908 -8.549894)
			(size 0.4572 0.4572)
			(layers "F.Cu" "F.Mask" "F.Paste")
			(net "GND")
		)
		(pad "T41" smd circle
			(at 15.200122 -8.549894)
			(size 0.4572 0.4572)
			(layers "F.Cu" "F.Mask" "F.Paste")
			(net "P5E_PEX1_STN4_TX_DP<64>")
		)
		(pad "T42" smd circle
			(at 16.150082 -8.549894)
			(size 0.4572 0.4572)
			(layers "F.Cu" "F.Mask" "F.Paste")
			(net "P5E_PEX1_STN4_TX_DN<64>")
		)
		(pad "T43" smd circle
			(at 17.100042 -8.549894)
			(size 0.4572 0.4572)
			(layers "F.Cu" "F.Mask" "F.Paste")
			(net "GND")
		)
		(pad "T44" smd circle
			(at 18.050002 -8.549894)
			(size 0.4572 0.4572)
			(layers "F.Cu" "F.Mask" "F.Paste")
			(net "GND")
		)
		(pad "T45" smd circle
			(at 18.999962 -8.549894)
			(size 0.4572 0.4572)
			(layers "F.Cu" "F.Mask" "F.Paste")
			(net "GND")
		)
		(pad "T46" smd circle
			(at 19.949922 -8.549894)
			(size 0.4572 0.4572)
			(layers "F.Cu" "F.Mask" "F.Paste")
			(net "GND")
		)
		(pad "T47" smd circle
			(at 20.899882 -8.549894)
			(size 0.4572 0.4572)
			(layers "F.Cu" "F.Mask" "F.Paste")
			(net "GND")
		)
		(pad "T48" smd circle
			(at 21.850096 -8.549894)
			(size 0.4572 0.4572)
			(layers "F.Cu" "F.Mask" "F.Paste")
			(net "P5E_PEX1_STN4_RX_DP<64>")
		)
		(pad "T49" smd circle
			(at 22.800056 -8.549894)
			(size 0.4572 0.4572)
			(layers "F.Cu" "F.Mask" "F.Paste")
			(net "P5E_PEX1_STN4_RX_DN<64>")
		)
		(pad "U1" smd circle
			(at -22.800056 -7.599934)
			(size 0.4572 0.4572)
			(layers "F.Cu" "F.Mask" "F.Paste")
			(net "GND")
		)
		(pad "U2" smd circle
			(at -21.850096 -7.599934)
			(size 0.4572 0.4572)
			(layers "F.Cu" "F.Mask" "F.Paste")
			(net "GND")
		)
		(pad "U3" smd circle
			(at -20.899882 -7.599934)
			(size 0.4572 0.4572)
			(layers "F.Cu" "F.Mask" "F.Paste")
			(net "P5E_PEX1_STN7_RX_DN<114>")
		)
		(pad "U4" smd circle
			(at -19.949922 -7.599934)
			(size 0.4572 0.4572)
			(layers "F.Cu" "F.Mask" "F.Paste")
			(net "P5E_PEX1_STN7_RX_DP<114>")
		)
		(pad "U5" smd circle
			(at -18.999962 -7.599934)
			(size 0.4572 0.4572)
			(layers "F.Cu" "F.Mask" "F.Paste")
			(net "GND")
		)
		(pad "U6" smd circle
			(at -18.050002 -7.599934)
			(size 0.4572 0.4572)
			(layers "F.Cu" "F.Mask" "F.Paste")
			(net "P5E_PEX1_STN7_TX_DN<114>")
		)
		(pad "U7" smd circle
			(at -17.100042 -7.599934)
			(size 0.4572 0.4572)
			(layers "F.Cu" "F.Mask" "F.Paste")
			(net "P5E_PEX1_STN7_TX_DP<114>")
		)
		(pad "U8" smd circle
			(at -16.150082 -7.599934)
			(size 0.4572 0.4572)
			(layers "F.Cu" "F.Mask" "F.Paste")
			(net "GND")
		)
		(pad "U9" smd circle
			(at -15.200122 -7.599934)
			(size 0.4572 0.4572)
			(layers "F.Cu" "F.Mask" "F.Paste")
			(net "GND")
		)
		(pad "U10" smd circle
			(at -14.249908 -7.599934)
			(size 0.4572 0.4572)
			(layers "F.Cu" "F.Mask" "F.Paste")
			(net "GND")
		)
		(pad "U11" smd circle
			(at -13.299948 -7.599934)
			(size 0.4572 0.4572)
			(layers "F.Cu" "F.Mask" "F.Paste")
			(net "GND")
		)
		(pad "U12" smd circle
			(at -12.349988 -7.599934)
			(size 0.4572 0.4572)
			(layers "F.Cu" "F.Mask" "F.Paste")
			(net "GND")
		)
		(pad "U13" smd circle
			(at -11.400028 -7.599934)
			(size 0.4572 0.4572)
			(layers "F.Cu" "F.Mask" "F.Paste")
			(net "GND")
		)
		(pad "U14" smd circle
			(at -10.450068 -7.599934)
			(size 0.4572 0.4572)
			(layers "F.Cu" "F.Mask" "F.Paste")
			(net "Net_499")
		)
		(pad "U15" smd circle
			(at -9.500108 -7.599934)
			(size 0.4572 0.4572)
			(layers "F.Cu" "F.Mask" "F.Paste")
			(net "GND")
		)
		(pad "U16" smd circle
			(at -8.549894 -7.599934)
			(size 0.4572 0.4572)
			(layers "F.Cu" "F.Mask" "F.Paste")
			(net "GND")
		)
		(pad "U17" smd circle
			(at -7.599934 -7.599934)
			(size 0.4572 0.4572)
			(layers "F.Cu" "F.Mask" "F.Paste")
			(net "GND")
		)
		(pad "U18" smd circle
			(at -6.649974 -7.599934)
			(size 0.4572 0.4572)
			(layers "F.Cu" "F.Mask" "F.Paste")
			(net "GND")
		)
		(pad "U19" smd circle
			(at -5.700014 -7.599934)
			(size 0.4572 0.4572)
			(layers "F.Cu" "F.Mask" "F.Paste")
			(net "GND")
		)
		(pad "U20" smd circle
			(at -4.750054 -7.599934)
			(size 0.4572 0.4572)
			(layers "F.Cu" "F.Mask" "F.Paste")
			(net "GND")
		)
		(pad "U21" smd circle
			(at -3.800094 -7.599934)
			(size 0.4572 0.4572)
			(layers "F.Cu" "F.Mask" "F.Paste")
			(net "GND")
		)
		(pad "U22" smd circle
			(at -2.84988 -7.599934)
			(size 0.4572 0.4572)
			(layers "F.Cu" "F.Mask" "F.Paste")
			(net "GND")
		)
		(pad "U23" smd circle
			(at -1.89992 -7.599934)
			(size 0.4572 0.4572)
			(layers "F.Cu" "F.Mask" "F.Paste")
			(net "GND")
		)
		(pad "U24" smd circle
			(at -0.94996 -7.599934)
			(size 0.4572 0.4572)
			(layers "F.Cu" "F.Mask" "F.Paste")
			(net "GND")
		)
		(pad "U25" smd circle
			(at 0 -7.599934)
			(size 0.4572 0.4572)
			(layers "F.Cu" "F.Mask" "F.Paste")
			(net "GND")
		)
		(pad "U26" smd circle
			(at 0.94996 -7.599934)
			(size 0.4572 0.4572)
			(layers "F.Cu" "F.Mask" "F.Paste")
			(net "GND")
		)
		(pad "U27" smd circle
			(at 1.89992 -7.599934)
			(size 0.4572 0.4572)
			(layers "F.Cu" "F.Mask" "F.Paste")
			(net "GND")
		)
		(pad "U28" smd circle
			(at 2.84988 -7.599934)
			(size 0.4572 0.4572)
			(layers "F.Cu" "F.Mask" "F.Paste")
			(net "GND")
		)
		(pad "U29" smd circle
			(at 3.800094 -7.599934)
			(size 0.4572 0.4572)
			(layers "F.Cu" "F.Mask" "F.Paste")
			(net "GND")
		)
		(pad "U30" smd circle
			(at 4.750054 -7.599934)
			(size 0.4572 0.4572)
			(layers "F.Cu" "F.Mask" "F.Paste")
			(net "GND")
		)
		(pad "U31" smd circle
			(at 5.700014 -7.599934)
			(size 0.4572 0.4572)
			(layers "F.Cu" "F.Mask" "F.Paste")
			(net "GND")
		)
		(pad "U32" smd circle
			(at 6.649974 -7.599934)
			(size 0.4572 0.4572)
			(layers "F.Cu" "F.Mask" "F.Paste")
			(net "GND")
		)
		(pad "U33" smd circle
			(at 7.599934 -7.599934)
			(size 0.4572 0.4572)
			(layers "F.Cu" "F.Mask" "F.Paste")
			(net "GND")
		)
		(pad "U34" smd circle
			(at 8.549894 -7.599934)
			(size 0.4572 0.4572)
			(layers "F.Cu" "F.Mask" "F.Paste")
			(net "GND")
		)
		(pad "U35" smd circle
			(at 9.500108 -7.599934)
			(size 0.4572 0.4572)
			(layers "F.Cu" "F.Mask" "F.Paste")
			(net "GND")
		)
		(pad "U36" smd circle
			(at 10.450068 -7.599934)
			(size 0.4572 0.4572)
			(layers "F.Cu" "F.Mask" "F.Paste")
			(net "Net_508")
		)
	)
)
